# S9S_MB_2U (Grand Teton) — schematic netlist excerpt (pin names and nets, part order shuffled) for the footprints in the layout excerpt that follows; sources: Cadence DE-HDL packaged netlist, KiCad conversion of 03242023_DA0F0TMBIJ0_F0T_Motherboard_J_brd_V01_OCP.brd

ME3  ME_DUMMY_SYMBOL  PICKUP_SMDC20 EMPTY  pkg PICKUP_SMDC20  page 312
C2314  Q_CAP  0.1UF 25V 10% EMPTY  pkg 0402  page 196 : A = P3V3_AUX_USB_HUB_2 ; B = GND
R662  Q_RES  499 1% CHIP  pkg 0402LF  page 230 : A = PVNN_TERM_CPU1 ; B = I3C_SPD_DDRABCD_CPU1_SCL

(kicad_pcb
	(version 20260206)
	(generator "pcbnew")
	(generator_version "10.0")
	(general
		(thickness 1.6)
		(legacy_teardrops no)
	)
	(paper "A4")
	(title_block
		(title "03242023_DA0F0TMBIJ0_F0T_Motherboard_J_brd_V01_OCP.brd")
		(comment 1 "Grand Teton / footprints 4382-4384 of 6105")
	)
	(layers
		(0 "F.Cu" signal "TOP")
		(4 "In1.Cu" signal "GND")
		(6 "In2.Cu" signal "IN1")
		(8 "In3.Cu" signal "GND1")
		(10 "In4.Cu" signal "IN2")
		(12 "In5.Cu" signal "GND2")
		(14 "In6.Cu" signal "IN3")
		(16 "In7.Cu" signal "GND3")
		(18 "In8.Cu" signal "VCC")
		(20 "In9.Cu" signal "VCC1")
		(22 "In10.Cu" signal "GND4")
		(24 "In11.Cu" signal "IN4")
		(26 "In12.Cu" signal "GND5")
		(28 "In13.Cu" signal "IN5")
		(30 "In14.Cu" signal "GND6")
		(32 "In15.Cu" signal "IN6")
		(34 "In16.Cu" signal "GND7")
		(2 "B.Cu" signal "BOTTOM")
		(9 "F.Adhes" user "F.Adhesive")
		(11 "B.Adhes" user "B.Adhesive")
		(13 "F.Paste" user "Package Geometry/Pastemask Top")
		(15 "B.Paste" user "Package Geometry/Pastemask Bottom")
		(5 "F.SilkS" user "Ref Des/Silkscreen Top")
		(7 "B.SilkS" user "Ref Des/Silkscreen Bottom")
		(1 "F.Mask" user "Board Geometry/Soldermask Top")
		(3 "B.Mask" user "Board Geometry/Soldermask Bottom")
		(17 "Dwgs.User" user "User.Drawings")
		(19 "Cmts.User" user "User.Comments")
		(21 "Eco1.User" user "User.Eco1")
		(23 "Eco2.User" user "User.Eco2")
		(25 "Edge.Cuts" user "Board Geometry/Outline")
		(27 "Margin" user)
		(31 "F.CrtYd" user "Package Geometry/Place Bound Top")
		(29 "B.CrtYd" user "Package Geometry/Place Bound Bottom")
		(35 "F.Fab" user "Ref Des/Assembly Top")
		(33 "B.Fab" user "Ref Des/Assembly Bottom")
	)
	(footprint ""
		(layer "B.Cu")
		(at 158.707074 -41.816528 -90)
		(property "Reference" "C2314"
			(at 0 0 90)
			(layer "B.SilkS")
			(hide yes)
			(effects
				(font
					(size 1.27 1.27)
				)
				(justify mirror)
			)
		)
		(property "Value" ""
			(at 0 0 90)
			(layer "B.Fab")
			(effects
				(font
					(size 1.27 1.27)
				)
				(justify mirror)
			)
		)
		(duplicate_pad_numbers_are_jumpers no)
		(fp_line
			(start -0.7874 0.4064)
			(end 0.7874 0.4064)
			(stroke
				(width 0.1524)
				(type default)
			)
			(layer "B.SilkS")
		)
		(fp_line
			(start 0.7874 0.4064)
			(end 0.7874 -0.4064)
			(stroke
				(width 0.1524)
				(type default)
			)
			(layer "B.SilkS")
		)
		(fp_line
			(start -0.7874 -0.4064)
			(end -0.7874 0.4064)
			(stroke
				(width 0.1524)
				(type default)
			)
			(layer "B.SilkS")
		)
		(fp_line
			(start 0.7874 -0.4064)
			(end -0.7874 -0.4064)
			(stroke
				(width 0.1524)
				(type default)
			)
			(layer "B.SilkS")
		)
		(fp_line
			(start -0.67945 0.3048)
			(end -0.120396 0.3048)
			(stroke
				(width 0.1)
				(type default)
			)
			(layer "B.Fab")
		)
		(fp_line
			(start -0.120396 0.3048)
			(end -0.120396 0.2794)
			(stroke
				(width 0.1)
				(type default)
			)
			(layer "B.Fab")
		)
		(fp_line
			(start 0.12065 0.3048)
			(end 0.67945 0.3048)
			(stroke
				(width 0.1)
				(type default)
			)
			(layer "B.Fab")
		)
		(fp_line
			(start 0.67945 0.3048)
			(end 0.67945 -0.305054)
			(stroke
				(width 0.1)
				(type default)
			)
			(layer "B.Fab")
		)
		(fp_line
			(start -0.120396 0.2794)
			(end 0.12065 0.2794)
			(stroke
				(width 0.1)
				(type default)
			)
			(layer "B.Fab")
		)
		(fp_line
			(start 0.12065 0.2794)
			(end 0.12065 0.3048)
			(stroke
				(width 0.1)
				(type default)
			)
			(layer "B.Fab")
		)
		(fp_line
			(start -0.12065 -0.2794)
			(end -0.12065 -0.3048)
			(stroke
				(width 0.1)
				(type default)
			)
			(layer "B.Fab")
		)
		(fp_line
			(start 0.12065 -0.2794)
			(end -0.12065 -0.2794)
			(stroke
				(width 0.1)
				(type default)
			)
			(layer "B.Fab")
		)
		(fp_line
			(start -0.67945 -0.3048)
			(end -0.67945 0.3048)
			(stroke
				(width 0.1)
				(type default)
			)
			(layer "B.Fab")
		)
		(fp_line
			(start -0.12065 -0.3048)
			(end -0.67945 -0.3048)
			(stroke
				(width 0.1)
				(type default)
			)
			(layer "B.Fab")
		)
		(fp_line
			(start 0.12065 -0.305054)
			(end 0.12065 -0.2794)
			(stroke
				(width 0.1)
				(type default)
			)
			(layer "B.Fab")
		)
		(fp_line
			(start 0.67945 -0.305054)
			(end 0.12065 -0.305054)
			(stroke
				(width 0.1)
				(type default)
			)
			(layer "B.Fab")
		)
		(pad "1" smd circle
			(at 0.40005 0 90)
			(size 0 0)
			(layers "B.Cu" "B.Mask" "B.Paste")
			(net "P3V3_AUX_USB_HUB_2")
		)
		(pad "2" smd circle
			(at -0.40005 0 90)
			(size 0 0)
			(layers "B.Cu" "B.Mask" "B.Paste")
			(net "GND")
		)
	)
	(footprint ""
		(layer "B.Cu")
		(at 96.8248 -128.91516)
		(property "Reference" "ME3"
			(at 9.652 -9.540748 0)
			(unlocked yes)
			(layer "B.SilkS")
			(effects
				(font
					(size 0.7874 0.5842)
					(thickness 0.1524)
				)
				(justify left mirror)
			)
		)
		(property "Value" ""
			(at 0 0 0)
			(layer "B.Fab")
			(effects
				(font
					(size 1.27 1.27)
				)
				(justify mirror)
			)
		)
		(duplicate_pad_numbers_are_jumpers no)
		(zone
			(layer "B.Cu")
			(hatch none 0.5)
			(connect_pads
				(clearance 0)
			)
			(min_thickness 0.25)
			(keepout
				(tracks allowed)
				(vias allowed)
				(pads allowed)
				(copperpour allowed)
				(footprints not_allowed)
			)
			(placement
				(enabled no)
				(sheetname "")
			)
			(fill
				(thermal_gap 0.5)
				(thermal_bridge_width 0.5)
				(island_removal_mode 0)
			)
			(polygon
				(pts
					(arc
						(start 106.82478 -128.91516)
						(mid 86.82482 -128.91516)
						(end 106.82478 -128.91516)
					)
				)
			)
		)
	)
	(footprint ""
		(layer "B.Cu")
		(at 92.177108 -190.705232 -90)
		(property "Reference" "R662"
			(at 0 0 90)
			(layer "B.SilkS")
			(hide yes)
			(effects
				(font
					(size 1.27 1.27)
				)
				(justify mirror)
			)
		)
		(property "Value" ""
			(at 0 0 90)
			(layer "B.Fab")
			(effects
				(font
					(size 1.27 1.27)
				)
				(justify mirror)
			)
		)
		(duplicate_pad_numbers_are_jumpers no)
		(fp_line
			(start -0.7874 0.4064)
			(end 0.7874 0.4064)
			(stroke
				(width 0.1524)
				(type default)
			)
			(layer "B.SilkS")
		)
		(fp_line
			(start 0.7874 0.4064)
			(end 0.7874 -0.4064)
			(stroke
				(width 0.1524)
				(type default)
			)
			(layer "B.SilkS")
		)
		(fp_line
			(start -0.7874 -0.4064)
			(end -0.7874 0.4064)
			(stroke
				(width 0.1524)
				(type default)
			)
			(layer "B.SilkS")
		)
		(fp_line
			(start 0.7874 -0.4064)
			(end -0.7874 -0.4064)
			(stroke
				(width 0.1524)
				(type default)
			)
			(layer "B.SilkS")
		)
		(fp_line
			(start -0.67945 0.3048)
			(end -0.120396 0.3048)
			(stroke
				(width 0.1)
				(type default)
			)
			(layer "B.Fab")
		)
		(fp_line
			(start -0.120396 0.3048)
			(end -0.120396 0.2794)
			(stroke
				(width 0.1)
				(type default)
			)
			(layer "B.Fab")
		)
		(fp_line
			(start 0.12065 0.3048)
			(end 0.67945 0.3048)
			(stroke
				(width 0.1)
				(type default)
			)
			(layer "B.Fab")
		)
		(fp_line
			(start 0.67945 0.3048)
			(end 0.67945 -0.305054)
			(stroke
				(width 0.1)
				(type default)
			)
			(layer "B.Fab")
		)
		(fp_line
			(start -0.120396 0.2794)
			(end 0.12065 0.2794)
			(stroke
				(width 0.1)
				(type default)
			)
			(layer "B.Fab")
		)
		(fp_line
			(start 0.12065 0.2794)
			(end 0.12065 0.3048)
			(stroke
				(width 0.1)
				(type default)
			)
			(layer "B.Fab")
		)
		(fp_line
			(start -0.12065 -0.2794)
			(end -0.12065 -0.3048)
			(stroke
				(width 0.1)
				(type default)
			)
			(layer "B.Fab")
		)
		(fp_line
			(start 0.12065 -0.2794)
			(end -0.12065 -0.2794)
			(stroke
				(width 0.1)
				(type default)
			)
			(layer "B.Fab")
		)
		(fp_line
			(start -0.67945 -0.3048)
			(end -0.67945 0.3048)
			(stroke
				(width 0.1)
				(type default)
			)
			(layer "B.Fab")
		)
		(fp_line
			(start -0.12065 -0.3048)
			(end -0.67945 -0.3048)
			(stroke
				(width 0.1)
				(type default)
			)
			(layer "B.Fab")
		)
		(fp_line
			(start 0.12065 -0.305054)
			(end 0.12065 -0.2794)
			(stroke
				(width 0.1)
				(type default)
			)
			(layer "B.Fab")
		)
		(fp_line
			(start 0.67945 -0.305054)
			(end 0.12065 -0.305054)
			(stroke
				(width 0.1)
				(type default)
			)
			(layer "B.Fab")
		)
		(pad "1" smd circle
			(at 0.40005 0 90)
			(size 0 0)
			(layers "B.Cu" "B.Mask" "B.Paste")
			(net "PVNN_TERM_CPU1")
		)
		(pad "2" smd circle
			(at -0.40005 0 90)
			(size 0 0)
			(layers "B.Cu" "B.Mask" "B.Paste")
			(net "I3C_SPD_DDRABCD_CPU1_SCL")
		)
	)
)
